(kicad_pcb
	(version 20260206)
	(generator "pcbnew")
	(generator_version "10.0")
	(general
		(thickness 1.6)
		(legacy_teardrops no)
	)
	(paper "A4")
	(title_block
		(title "pdpb — Lightning_PDPB_BRD.brd")
		(comment 1 "Lightning (Wiwynn / Facebook NVMe JBOF) / footprints 456-456 of 1140")
	)
	(layers
		(0 "F.Cu" signal "TOP")
		(4 "In1.Cu" signal "L2GND")
		(6 "In2.Cu" signal "L3")
		(8 "In3.Cu" signal "L4VCC")
		(10 "In4.Cu" signal "L5VCC")
		(12 "In5.Cu" signal "L6")
		(14 "In6.Cu" signal "L7GND")
		(2 "B.Cu" signal "BOTTOM")
		(9 "F.Adhes" user "F.Adhesive")
		(11 "B.Adhes" user "B.Adhesive")
		(13 "F.Paste" user "Package Geometry/Pastemask Top")
		(15 "B.Paste" user "Package Geometry/Pastemask Bottom")
		(5 "F.SilkS" user "Ref Des/Silkscreen Top")
		(7 "B.SilkS" user "Ref Des/Silkscreen Bottom")
		(1 "F.Mask" user "Board Geometry/Soldermask Top")
		(3 "B.Mask" user "Board Geometry/Soldermask Bottom")
		(17 "Dwgs.User" user "User.Drawings")
		(19 "Cmts.User" user "User.Comments")
		(21 "Eco1.User" user "User.Eco1")
		(23 "Eco2.User" user "User.Eco2")
		(25 "Edge.Cuts" user "Board Geometry/Outline")
		(27 "Margin" user)
		(31 "F.CrtYd" user "Package Geometry/Place Bound Top")
		(29 "B.CrtYd" user "Package Geometry/Place Bound Bottom")
		(35 "F.Fab" user "Ref Des/Assembly Top")
		(33 "B.Fab" user "Ref Des/Assembly Bottom")
	)
	(footprint ""
		(layer "F.Cu")
		(at 20.850098 -232.32999 -90)
		(property "Reference" "J12"
			(at 0 0 270)
			(layer "F.SilkS")
			(hide yes)
			(effects
				(font
					(size 1.27 1.27)
				)
			)
		)
		(property "Value" "PCISLT68-14-GP-U1"
			(at -22.225 12.7508 270)
			(unlocked yes)
			(layer "F.Fab")
			(hide yes)
			(effects
				(font
					(size 1.016 1.016)
					(thickness 0.1524)
				)
			)
		)
		(property "Device Type" "SD-78827-0001"
			(at -22.225 11.2268 270)
			(unlocked yes)
			(layer "F.Fab")
			(hide yes)
			(effects
				(font
					(size 1.016 1.016)
					(thickness 0.1524)
				)
			)
		)
		(duplicate_pad_numbers_are_jumpers no)
		(fp_line
			(start -20.4724 12.0142)
			(end -20.4724 4.6736)
			(stroke
				(width 0.1524)
				(type default)
			)
			(layer "F.SilkS")
		)
		(fp_line
			(start -17.8435 12.0142)
			(end -20.4724 12.0142)
			(stroke
				(width 0.1524)
				(type default)
			)
			(layer "F.SilkS")
		)
		(fp_line
			(start 17.8435 12.0142)
			(end 17.8435 10.3124)
			(stroke
				(width 0.1524)
				(type default)
			)
			(layer "F.SilkS")
		)
		(fp_line
			(start 20.4724 12.0142)
			(end 17.8435 12.0142)
			(stroke
				(width 0.1524)
				(type default)
			)
			(layer "F.SilkS")
		)
		(fp_line
			(start -17.8435 10.3124)
			(end -17.8435 12.0142)
			(stroke
				(width 0.1524)
				(type default)
			)
			(layer "F.SilkS")
		)
		(fp_line
			(start 17.8435 10.3124)
			(end -17.8435 10.3124)
			(stroke
				(width 0.1524)
				(type default)
			)
			(layer "F.SilkS")
		)
		(fp_line
			(start -23.749 4.6736)
			(end -23.749 0.0254)
			(stroke
				(width 0.1524)
				(type default)
			)
			(layer "F.SilkS")
		)
		(fp_line
			(start -20.4724 4.6736)
			(end -23.749 4.6736)
			(stroke
				(width 0.1524)
				(type default)
			)
			(layer "F.SilkS")
		)
		(fp_line
			(start 20.4724 4.6736)
			(end 20.4724 12.0142)
			(stroke
				(width 0.1524)
				(type default)
			)
			(layer "F.SilkS")
		)
		(fp_line
			(start 23.749 4.6736)
			(end 20.4724 4.6736)
			(stroke
				(width 0.1524)
				(type default)
			)
			(layer "F.SilkS")
		)
		(fp_line
			(start -23.117556 2.896108)
			(end -23.117556 1.803908)
			(stroke
				(width 0.3048)
				(type default)
			)
			(layer "F.SilkS")
		)
		(fp_line
			(start 20.882356 2.896108)
			(end 20.882356 1.803908)
			(stroke
				(width 0.3048)
				(type default)
			)
			(layer "F.SilkS")
		)
		(fp_line
			(start -20.882356 1.803908)
			(end -20.882356 2.896108)
			(stroke
				(width 0.3048)
				(type default)
			)
			(layer "F.SilkS")
		)
		(fp_line
			(start 23.117556 1.803908)
			(end 23.117556 2.896108)
			(stroke
				(width 0.3048)
				(type default)
			)
			(layer "F.SilkS")
		)
		(fp_line
			(start -23.749 0.0254)
			(end -20.4724 0.0254)
			(stroke
				(width 0.1524)
				(type default)
			)
			(layer "F.SilkS")
		)
		(fp_line
			(start -20.4724 0.0254)
			(end -20.4724 -3.4036)
			(stroke
				(width 0.1524)
				(type default)
			)
			(layer "F.SilkS")
		)
		(fp_line
			(start 20.4724 0.0254)
			(end 23.749 0.0254)
			(stroke
				(width 0.1524)
				(type default)
			)
			(layer "F.SilkS")
		)
		(fp_line
			(start 23.749 0.0254)
			(end 23.749 4.6736)
			(stroke
				(width 0.1524)
				(type default)
			)
			(layer "F.SilkS")
		)
		(fp_line
			(start -20.4724 -3.4036)
			(end 20.4724 -3.4036)
			(stroke
				(width 0.1524)
				(type default)
			)
			(layer "F.SilkS")
		)
		(fp_line
			(start 20.4724 -3.4036)
			(end 20.4724 0.0254)
			(stroke
				(width 0.1524)
				(type default)
			)
			(layer "F.SilkS")
		)
		(fp_arc
			(start -20.882356 2.896108)
			(mid -21.999956 4.013708)
			(end -23.117556 2.896108)
			(stroke
				(width 0.3048)
				(type default)
			)
			(layer "F.SilkS")
		)
		(fp_arc
			(start 23.117556 2.896108)
			(mid 21.999956 4.013708)
			(end 20.882356 2.896108)
			(stroke
				(width 0.3048)
				(type default)
			)
			(layer "F.SilkS")
		)
		(fp_arc
			(start -23.117556 1.803908)
			(mid -21.999956 0.686308)
			(end -20.882356 1.803908)
			(stroke
				(width 0.3048)
				(type default)
			)
			(layer "F.SilkS")
		)
		(fp_arc
			(start 20.882356 1.803908)
			(mid 21.999956 0.686308)
			(end 23.117556 1.803908)
			(stroke
				(width 0.3048)
				(type default)
			)
			(layer "F.SilkS")
		)
		(fp_poly
			(pts
				(xy -20.2184 11.7602) (xy -20.2184 4.4196) (xy -23.495 4.4196) (xy -23.495 0.2794) (xy -20.2184 0.2794)
				(xy -20.2184 -3.1496) (xy 20.2184 -3.1496) (xy 20.2184 0.2794) (xy 23.495 0.2794) (xy 23.495 4.4196)
				(xy 20.2184 4.4196) (xy 20.2184 11.7602) (xy 18.0975 11.7602) (xy 18.0975 10.0584) (xy -18.0975 10.0584)
				(xy -18.0975 11.7602)
			)
			(stroke
				(width 0)
				(type default)
			)
			(fill no)
			(layer "F.CrtYd")
		)
		(fp_poly
			(pts
				(xy -21.2471 16.256) (xy -21.2471 4.9276) (xy -24.003 4.9276) (xy -24.003 -0.2286) (xy -20.7264 -0.2286)
				(xy -20.7264 -3.6576) (xy 20.7264 -3.6576) (xy 20.7264 -0.2286) (xy 24.003 -0.2286) (xy 24.003 -0.00635)
				(xy 20.2184 -0.00635) (xy 20.2184 -3.1496) (xy -20.2184 -3.1496) (xy -20.2184 0.2794) (xy -23.495 0.2794)
				(xy -23.495 4.4196) (xy -20.2184 4.4196) (xy -20.2184 11.7602) (xy -18.0975 11.7602) (xy -18.0975 10.0584)
				(xy 18.0975 10.0584) (xy 18.0975 11.7602) (xy 20.2184 11.7602) (xy 20.2184 4.4196) (xy 23.495 4.4196)
				(xy 23.495 0.2794) (xy 20.2184 0.2794) (xy 20.2184 0.00635) (xy 24.003 0.00635) (xy 24.003 4.9276)
				(xy 21.2471 4.9276) (xy 21.2471 16.256)
			)
			(stroke
				(width 0)
				(type default)
			)
			(fill no)
			(layer "F.CrtYd")
		)
		(fp_poly
			(pts
				(xy -21.2471 16.256) (xy -21.2471 4.9276) (xy -24.003 4.9276) (xy -24.003 -0.2286) (xy -20.7264 -0.2286)
				(xy -20.7264 -3.6576) (xy 20.7264 -3.6576) (xy 20.7264 -0.2286) (xy 24.003 -0.2286) (xy 24.003 4.9276)
				(xy 21.2471 4.9276) (xy 21.2471 16.256)
			)
			(stroke
				(width 0)
				(type default)
			)
			(fill no)
			(layer "F.Fab")
		)
		(pad "" np_thru_hole circle
			(at -18.999962 0 270)
			(size 0.254 0.254)
			(drill 1.8542)
			(layers "*.Cu" "*.Mask")
			(clearance 1.1557)
			(thermal_gap 1.1557)
		)
		(pad "" np_thru_hole circle
			(at 18.999962 0 270)
			(size 0.254 0.254)
			(drill 1.8542)
			(layers "*.Cu" "*.Mask")
			(clearance 1.1557)
			(thermal_gap 1.1557)
		)
		(pad "E1" smd rect
			(at -7.079996 1.240028 270)
			(size 0.508 2.0066)
			(layers "F.Cu" "F.Mask" "F.Paste")
			(net "PE_CLK100M_DR12_2_P")
		)
		(pad "E2" smd rect
			(at -6.279896 1.240028 270)
			(size 0.508 2.0066)
			(layers "F.Cu" "F.Mask" "F.Paste")
			(net "PE_CLK100M_DR12_2_N")
		)
		(pad "E3" smd rect
			(at -5.48005 1.240028 270)
			(size 0.508 2.0066)
			(layers "F.Cu" "F.Mask" "F.Paste")
			(net "P3V3")
		)
		(pad "E4" smd rect
			(at -4.67995 1.240028 270)
			(size 0.508 2.0066)
			(layers "F.Cu" "F.Mask" "F.Paste")
			(net "SSD12_PERST_N")
		)
		(pad "E5" smd rect
			(at -3.880104 1.240028 270)
			(size 0.508 2.0066)
			(layers "F.Cu" "F.Mask" "F.Paste")
			(net "SSD12_PERST_N")
		)
		(pad "E6" smd rect
			(at -3.080004 1.240028 270)
			(size 0.508 2.0066)
			(layers "F.Cu" "F.Mask" "F.Paste")
			(net "Net_1251")
		)
		(pad "E7" smd rect
			(at -15.48003 -1.949958 270)
			(size 0.508 2.0066)
			(layers "F.Cu" "F.Mask" "F.Paste")
			(net "PE_CLK100M_DR12_1_P")
		)
		(pad "E8" smd rect
			(at -14.67993 -1.949958 270)
			(size 0.508 2.0066)
			(layers "F.Cu" "F.Mask" "F.Paste")
			(net "PE_CLK100M_DR12_1_N")
		)
		(pad "E9" smd rect
			(at -13.880084 -1.949958 270)
			(size 0.508 2.0066)
			(layers "F.Cu" "F.Mask" "F.Paste")
			(net "GND")
		)
		(pad "E10" smd rect
			(at -13.079984 -1.949958 270)
			(size 0.508 2.0066)
			(layers "F.Cu" "F.Mask" "F.Paste")
			(net "PE_TX1_DR12_N")
		)
		(pad "E11" smd rect
			(at -12.279884 -1.949958 270)
			(size 0.508 2.0066)
			(layers "F.Cu" "F.Mask" "F.Paste")
			(net "PE_TX1_DR12_P")
		)
		(pad "E12" smd rect
			(at -11.480038 -1.949958 270)
			(size 0.508 2.0066)
			(layers "F.Cu" "F.Mask" "F.Paste")
			(net "GND")
		)
		(pad "E13" smd rect
			(at -10.679938 -1.949958 270)
			(size 0.508 2.0066)
			(layers "F.Cu" "F.Mask" "F.Paste")
			(net "PE_RX1_DR12_N")
		)
		(pad "E14" smd rect
			(at -9.880092 -1.949958 270)
			(size 0.508 2.0066)
			(layers "F.Cu" "F.Mask" "F.Paste")
			(net "PE_RX1_DR12_P")
		)
		(pad "E15" smd rect
			(at -9.079992 -1.949958 270)
			(size 0.508 2.0066)
			(layers "F.Cu" "F.Mask" "F.Paste")
			(net "GND")
		)
		(pad "E16" smd rect
			(at -8.279892 -1.949958 270)
			(size 0.508 2.0066)
			(layers "F.Cu" "F.Mask" "F.Paste")
			(net "Net_1258")
		)
		(pad "E17" smd rect
			(at 9.320022 -1.949958 270)
			(size 0.508 2.0066)
			(layers "F.Cu" "F.Mask" "F.Paste")
			(net "PE_TX4_DR12_N")
		)
		(pad "E18" smd rect
			(at 10.120122 -1.949958 270)
			(size 0.508 2.0066)
			(layers "F.Cu" "F.Mask" "F.Paste")
			(net "PE_TX4_DR12_P")
		)
		(pad "E19" smd rect
			(at 10.919968 -1.949958 270)
			(size 0.508 2.0066)
			(layers "F.Cu" "F.Mask" "F.Paste")
			(net "GND")
		)
		(pad "E20" smd rect
			(at 11.720068 -1.949958 270)
			(size 0.508 2.0066)
			(layers "F.Cu" "F.Mask" "F.Paste")
			(net "PE_RX4_DR12_N")
		)
		(pad "E21" smd rect
			(at 12.519914 -1.949958 270)
			(size 0.508 2.0066)
			(layers "F.Cu" "F.Mask" "F.Paste")
			(net "PE_RX4_DR12_P")
		)
		(pad "E22" smd rect
			(at 13.320014 -1.949958 270)
			(size 0.508 2.0066)
			(layers "F.Cu" "F.Mask" "F.Paste")
			(net "GND")
		)
		(pad "E23" smd rect
			(at 14.120114 -1.949958 270)
			(size 0.508 2.0066)
			(layers "F.Cu" "F.Mask" "F.Paste")
			(net "SCL_DR12_R")
		)
		(pad "E24" smd rect
			(at 14.91996 -1.949958 270)
			(size 0.508 2.0066)
			(layers "F.Cu" "F.Mask" "F.Paste")
			(net "SDA_DR12_R")
		)
		(pad "E25" smd rect
			(at 15.72006 -1.949958 270)
			(size 0.508 2.0066)
			(layers "F.Cu" "F.Mask" "F.Paste")
			(net "DUALPORTEN#12")
		)
		(pad "P1" smd rect
			(at -1.905 0.824992 270)
			(size 0.6604 2.0574)
			(layers "F.Cu" "F.Mask" "F.Paste")
			(net "Net_1254")
		)
		(pad "P2" smd rect
			(at -0.635 0.824992 270)
			(size 0.6604 2.0574)
			(layers "F.Cu" "F.Mask" "F.Paste")
			(net "Net_1253")
		)
		(pad "P3" smd rect
			(at 0.635 0.824992 270)
			(size 0.6604 2.0574)
			(layers "F.Cu" "F.Mask" "F.Paste")
			(net "Net_1252")
		)
		(pad "P4" smd rect
			(at 1.905 0.824992 270)
			(size 0.6604 2.0574)
			(layers "F.Cu" "F.Mask" "F.Paste")
			(net "SSD12_CLK0_OE_N")
		)
		(pad "P5" smd rect
			(at 3.175 0.824992 270)
			(size 0.6604 2.0574)
			(layers "F.Cu" "F.Mask" "F.Paste")
			(net "GND")
		)
		(pad "P6" smd rect
			(at 4.445 0.824992 270)
			(size 0.6604 2.0574)
			(layers "F.Cu" "F.Mask" "F.Paste")
			(net "GND")
		)
		(pad "P7" smd rect
			(at 5.715 0.824992 270)
			(size 0.6604 2.0574)
			(layers "F.Cu" "F.Mask" "F.Paste")
			(net "Net_98")
		)
		(pad "P8" smd rect
			(at 6.985 0.824992 270)
			(size 0.6604 2.0574)
			(layers "F.Cu" "F.Mask" "F.Paste")
			(net "Net_70")
		)
		(pad "P9" smd rect
			(at 8.255 0.824992 270)
			(size 0.6604 2.0574)
			(layers "F.Cu" "F.Mask" "F.Paste")
			(net "Net_84")
		)
		(pad "P10" smd rect
			(at 9.525 0.824992 270)
			(size 0.6604 2.0574)
			(layers "F.Cu" "F.Mask" "F.Paste")
			(net "SSD_PRSNT_NET12")
		)
		(pad "P11" smd rect
			(at 10.795 0.824992 270)
			(size 0.6604 2.0574)
			(layers "F.Cu" "F.Mask" "F.Paste")
			(net "SSD_ACT_DR12")
		)
		(pad "P12" smd rect
			(at 12.065 0.824992 270)
			(size 0.6604 2.0574)
			(layers "F.Cu" "F.Mask" "F.Paste")
			(net "GND")
		)
		(pad "P13" smd rect
			(at 13.335 0.824992 270)
			(size 0.6604 2.0574)
			(layers "F.Cu" "F.Mask" "F.Paste")
			(net "12V_PRECH_SSD12")
		)
		(pad "P14" smd rect
			(at 14.605 0.824992 270)
			(size 0.6604 2.0574)
			(layers "F.Cu" "F.Mask" "F.Paste")
			(net "P12V_SSD12")
		)
		(pad "P15" smd rect
			(at 15.875 0.824992 270)
			(size 0.6604 2.0574)
			(layers "F.Cu" "F.Mask" "F.Paste")
			(net "P12V_SSD12")
		)
		(pad "PTH1" thru_hole oval
			(at -21.999956 2.350008 270)
			(size 1.524 2.6162)
			(drill oval 0.8128 1.905)
			(layers "*.Cu" "*.Mask")
			(remove_unused_layers no)
			(net "Net_1263")
			(clearance 0.1524)
			(thermal_gap 0.1524)
		)
		(pad "PTH2" thru_hole oval
			(at 21.999956 2.350008 270)
			(size 1.524 2.6162)
			(drill oval 0.8128 1.905)
			(layers "*.Cu" "*.Mask")
			(remove_unused_layers no)
			(net "Net_1247")
			(clearance 0.1524)
			(thermal_gap 0.1524)
		)
		(pad "S1" smd rect
			(at -15.875 0.824992 270)
			(size 0.6604 2.0574)
			(layers "F.Cu" "F.Mask" "F.Paste")
			(net "GND")
		)
		(pad "S2" smd rect
			(at -14.605 0.824992 270)
			(size 0.6604 2.0574)
			(layers "F.Cu" "F.Mask" "F.Paste")
			(net "Net_1262")
		)
		(pad "S3" smd rect
			(at -13.335 0.824992 270)
			(size 0.6604 2.0574)
			(layers "F.Cu" "F.Mask" "F.Paste")
			(net "Net_1261")
		)
		(pad "S4" smd rect
			(at -12.065 0.824992 270)
			(size 0.6604 2.0574)
			(layers "F.Cu" "F.Mask" "F.Paste")
			(net "GND")
		)
		(pad "S5" smd rect
			(at -10.795 0.824992 270)
			(size 0.6604 2.0574)
			(layers "F.Cu" "F.Mask" "F.Paste")
			(net "Net_1260")
		)
		(pad "S6" smd rect
			(at -9.525 0.824992 270)
			(size 0.6604 2.0574)
			(layers "F.Cu" "F.Mask" "F.Paste")
			(net "Net_1259")
		)
		(pad "S7" smd rect
			(at -8.255 0.824992 270)
			(size 0.6604 2.0574)
			(layers "F.Cu" "F.Mask" "F.Paste")
			(net "GND")
		)
		(pad "S8" smd rect
			(at -7.480046 -1.949958 270)
			(size 0.508 2.0066)
			(layers "F.Cu" "F.Mask" "F.Paste")
			(net "GND")
		)
		(pad "S9" smd rect
			(at -6.679946 -1.949958 270)
			(size 0.508 2.0066)
			(layers "F.Cu" "F.Mask" "F.Paste")
			(net "Net_1257")
		)
		(pad "S10" smd rect
			(at -5.8801 -1.949958 270)
			(size 0.508 2.0066)
			(layers "F.Cu" "F.Mask" "F.Paste")
			(net "Net_1256")
		)
		(pad "S11" smd rect
			(at -5.08 -1.949958 270)
			(size 0.508 2.0066)
			(layers "F.Cu" "F.Mask" "F.Paste")
			(net "GND")
		)
		(pad "S12" smd rect
			(at -4.2799 -1.949958 270)
			(size 0.508 2.0066)
			(layers "F.Cu" "F.Mask" "F.Paste")
			(net "Net_1255")
		)
		(pad "S13" smd rect
			(at -3.480054 -1.949958 270)
			(size 0.508 2.0066)
			(layers "F.Cu" "F.Mask" "F.Paste")
			(net "Net_1250")
		)
		(pad "S14" smd rect
			(at -2.679954 -1.949958 270)
			(size 0.508 2.0066)
			(layers "F.Cu" "F.Mask" "F.Paste")
			(net "GND")
		)
		(pad "S15" smd rect
			(at -1.880108 -1.949958 270)
			(size 0.508 2.0066)
			(layers "F.Cu" "F.Mask" "F.Paste")
			(net "Net_1249")
		)
		(pad "S16" smd rect
			(at -1.080008 -1.949958 270)
			(size 0.508 2.0066)
			(layers "F.Cu" "F.Mask" "F.Paste")
			(net "GND")
		)
		(pad "S17" smd rect
			(at -0.279908 -1.949958 270)
			(size 0.508 2.0066)
			(layers "F.Cu" "F.Mask" "F.Paste")
			(net "PE_TX2_DR12_N")
		)
		(pad "S18" smd rect
			(at 0.519938 -1.949958 270)
			(size 0.508 2.0066)
			(layers "F.Cu" "F.Mask" "F.Paste")
			(net "PE_TX2_DR12_P")
		)
		(pad "S19" smd rect
			(at 1.320038 -1.949958 270)
			(size 0.508 2.0066)
			(layers "F.Cu" "F.Mask" "F.Paste")
			(net "GND")
		)
		(pad "S20" smd rect
			(at 2.119884 -1.949958 270)
			(size 0.508 2.0066)
			(layers "F.Cu" "F.Mask" "F.Paste")
			(net "PE_RX2_DR12_N")
		)
		(pad "S21" smd rect
			(at 2.919984 -1.949958 270)
			(size 0.508 2.0066)
			(layers "F.Cu" "F.Mask" "F.Paste")
			(net "PE_RX2_DR12_P")
		)
		(pad "S22" smd rect
			(at 3.720084 -1.949958 270)
			(size 0.508 2.0066)
			(layers "F.Cu" "F.Mask" "F.Paste")
			(net "GND")
		)
		(pad "S23" smd rect
			(at 4.51993 -1.949958 270)
			(size 0.508 2.0066)
			(layers "F.Cu" "F.Mask" "F.Paste")
			(net "PE_TX3_DR12_N")
		)
		(pad "S24" smd rect
			(at 5.32003 -1.949958 270)
			(size 0.508 2.0066)
			(layers "F.Cu" "F.Mask" "F.Paste")
			(net "PE_TX3_DR12_P")
		)
		(pad "S25" smd rect
			(at 6.119876 -1.949958 270)
			(size 0.508 2.0066)
			(layers "F.Cu" "F.Mask" "F.Paste")
			(net "GND")
		)
		(pad "S26" smd rect
			(at 6.919976 -1.949958 270)
			(size 0.508 2.0066)
			(layers "F.Cu" "F.Mask" "F.Paste")
			(net "PE_RX3_DR12_N")
		)
		(pad "S27" smd rect
			(at 7.720076 -1.949958 270)
			(size 0.508 2.0066)
			(layers "F.Cu" "F.Mask" "F.Paste")
			(net "PE_RX3_DR12_P")
		)
		(pad "S28" smd rect
			(at 8.519922 -1.949958 270)
			(size 0.508 2.0066)
			(layers "F.Cu" "F.Mask" "F.Paste")
			(net "GND")
		)
		(zone
			(layers "F.Cu" "B.Cu" "In1.Cu" "In2.Cu" "In3.Cu" "In4.Cu" "In5.Cu" "In6.Cu")
			(hatch none 0.5)
			(connect_pads
				(clearance 0)
			)
			(min_thickness 0.25)
			(keepout
				(tracks not_allowed)
				(vias allowed)
				(pads allowed)
				(copperpour not_allowed)
				(footprints allowed)
			)
			(placement
				(enabled no)
				(sheetname "")
			)
			(fill
				(thermal_gap 0.5)
				(thermal_bridge_width 0.5)
				(island_removal_mode 0)
			)
			(polygon
				(pts
					(arc
						(start 22.081998 -251.329952)
						(mid 19.618198 -251.329952)
						(end 22.081998 -251.329952)
					)
				)
			)
		)
		(zone
			(layers "F.Cu" "B.Cu" "In1.Cu" "In2.Cu" "In3.Cu" "In4.Cu" "In5.Cu" "In6.Cu")
			(hatch none 0.5)
			(connect_pads
				(clearance 0)
			)
			(min_thickness 0.25)
			(keepout
				(tracks not_allowed)
				(vias allowed)
				(pads allowed)
				(copperpour not_allowed)
				(footprints allowed)
			)
			(placement
				(enabled no)
				(sheetname "")
			)
			(fill
				(thermal_gap 0.5)
				(thermal_bridge_width 0.5)
				(island_removal_mode 0)
			)
			(polygon
				(pts
					(arc
						(start 22.081998 -213.330028)
						(mid 19.618198 -213.330028)
						(end 22.081998 -213.330028)
					)
				)
			)
		)
	)
)
